(kicad_pcb
	(version 20240108)
	(generator "pcbnew")
	(generator_version "8.0")
	(general
		(thickness 1.6)
		(legacy_teardrops no)
	)
	(paper "A4")
	(title_block
		(title "Jetson Orin Baseboard OCuLink Expansion")
		(date "2025-03-18")
		(rev "1.1.0")
		(company "Antmicro Ltd")
		(comment 1 "www.antmicro.com")
		(comment 9 "footprints 82-85 of 119")
	)
	(layers
		(0 "F.Cu" signal)
		(1 "In1.Cu" signal)
		(2 "In2.Cu" signal)
		(31 "B.Cu" signal)
		(32 "B.Adhes" user "B.Adhesive")
		(33 "F.Adhes" user "F.Adhesive")
		(34 "B.Paste" user)
		(35 "F.Paste" user)
		(36 "B.SilkS" user "B.Silkscreen")
		(37 "F.SilkS" user "F.Silkscreen")
		(38 "B.Mask" user)
		(39 "F.Mask" user)
		(40 "Dwgs.User" user "User.Drawings")
		(41 "Cmts.User" user "User.Comments")
		(42 "Eco1.User" user "User.Eco1")
		(43 "Eco2.User" user "User.Eco2")
		(44 "Edge.Cuts" user)
		(45 "Margin" user)
		(46 "B.CrtYd" user "B.Courtyard")
		(47 "F.CrtYd" user "F.Courtyard")
		(48 "B.Fab" user)
		(49 "F.Fab" user)
	)
	(footprint "antmicro-footprints:C_0402_1005Metric"
		(layer "B.Cu")
		(at 123.505 114.569251 90)
		(descr "Capacitor SMD 0402")
		(tags "capacitor SMD 0402")
		(property "Reference" "C23"
			(at 1.779251 -0.355 90)
			(layer "B.SilkS")
			(effects
				(font
					(size 0.7 0.7)
					(thickness 0.15)
				)
				(justify right top mirror)
			)
		)
		(property "Value" "C_100n_0402"
			(at -1.022927 -2.155213 90)
			(layer "B.Fab")
			(effects
				(font
					(size 0.7 0.7)
					(thickness 0.15)
				)
				(justify right top mirror)
			)
		)
		(property "Footprint" "antmicro-footprints:C_0402_1005Metric"
			(at 0 0 90)
			(layer "B.Fab")
			(hide yes)
			(effects
				(font
					(size 1.27 1.27)
					(thickness 0.15)
				)
				(justify mirror)
			)
		)
		(property "Datasheet" "https://www.murata.com/products/productdetail?partno=GRM155R61H104KE14%23"
			(at 0 0 90)
			(layer "B.Fab")
			(hide yes)
			(effects
				(font
					(size 1.27 1.27)
					(thickness 0.15)
				)
				(justify mirror)
			)
		)
		(property "Description" "SMD Multilayer Ceramic Capacitor, 0.1 µF, 50 V, 0402 [1005 Metric], ± 10%, X5R, GRM Series"
			(at 0 0 90)
			(layer "B.Fab")
			(hide yes)
			(effects
				(font
					(size 1.27 1.27)
					(thickness 0.15)
				)
				(justify mirror)
			)
		)
		(property "MPN" "GRM155R61H104KE14D"
			(at 0 0 -90)
			(unlocked yes)
			(layer "B.Fab")
			(hide yes)
			(effects
				(font
					(size 1 1)
					(thickness 0.15)
				)
				(justify mirror)
			)
		)
		(property "Manufacturer" "Murata"
			(at 0 0 -90)
			(unlocked yes)
			(layer "B.Fab")
			(hide yes)
			(effects
				(font
					(size 1 1)
					(thickness 0.15)
				)
				(justify mirror)
			)
		)
		(property "License" "Apache-2.0"
			(at 0 0 -90)
			(unlocked yes)
			(layer "B.Fab")
			(hide yes)
			(effects
				(font
					(size 1 1)
					(thickness 0.15)
				)
				(justify mirror)
			)
		)
		(property "Author" "Antmicro"
			(at 0 0 -90)
			(unlocked yes)
			(layer "B.Fab")
			(hide yes)
			(effects
				(font
					(size 1 1)
					(thickness 0.15)
				)
				(justify mirror)
			)
		)
		(property "Val" "100n"
			(at 0 0 -90)
			(unlocked yes)
			(layer "B.Fab")
			(hide yes)
			(effects
				(font
					(size 1 1)
					(thickness 0.15)
				)
				(justify mirror)
			)
		)
		(property "Voltage" "50V"
			(at 0 0 -90)
			(unlocked yes)
			(layer "B.Fab")
			(hide yes)
			(effects
				(font
					(size 1 1)
					(thickness 0.15)
				)
				(justify mirror)
			)
		)
		(property "Dielectric" "X5R"
			(at 0 0 -90)
			(unlocked yes)
			(layer "B.Fab")
			(hide yes)
			(effects
				(font
					(size 1 1)
					(thickness 0.15)
				)
				(justify mirror)
			)
		)
		(property "Public" "False"
			(at 0 0 -90)
			(unlocked yes)
			(layer "B.Fab")
			(hide yes)
			(effects
				(font
					(size 1 1)
					(thickness 0.15)
				)
				(justify mirror)
			)
		)
		(sheetname "Root")
		(sheetfile "jetson-orin-baseboard-oculink-expansion.kicad_sch")
		(attr smd)
		(fp_rect
			(start -0.925 0.47)
			(end 0.925 -0.47)
			(stroke
				(width 0.05)
				(type default)
			)
			(fill none)
			(layer "B.CrtYd")
		)
		(fp_line
			(start 0.504 -0.248)
			(end 0.504 0.25)
			(stroke
				(width 0.15)
				(type solid)
			)
			(layer "B.Fab")
		)
		(fp_line
			(start -0.494 -0.248)
			(end 0.504 -0.248)
			(stroke
				(width 0.15)
				(type solid)
			)
			(layer "B.Fab")
		)
		(fp_line
			(start 0.504 0.25)
			(end -0.494 0.25)
			(stroke
				(width 0.15)
				(type solid)
			)
			(layer "B.Fab")
		)
		(fp_line
			(start -0.494 0.25)
			(end -0.494 -0.248)
			(stroke
				(width 0.15)
				(type solid)
			)
			(layer "B.Fab")
		)
		(fp_text user "${REFERENCE}"
			(at -0.939 -4.599 90)
			(layer "B.Fab")
			(hide yes)
			(effects
				(font
					(size 0.7 0.7)
					(thickness 0.15)
				)
				(justify right top mirror)
			)
		)
		(fp_text user "Author: Antmicro"
			(at -0.939 -3.399 90)
			(layer "B.Fab")
			(hide yes)
			(effects
				(font
					(size 0.7 0.7)
					(thickness 0.15)
				)
				(justify right top mirror)
			)
		)
		(fp_text user "License: Apache-2.0"
			(at -0.939 -5.799 90)
			(layer "B.Fab")
			(hide yes)
			(effects
				(font
					(size 0.7 0.7)
					(thickness 0.15)
				)
				(justify right top mirror)
			)
		)
		(pad "1" smd roundrect
			(at -0.48 0 90)
			(size 0.59 0.64)
			(layers "B.Cu" "B.Paste" "B.Mask")
			(roundrect_rratio 0.25)
			(net 51 "GND")
			(pintype "passive")
		)
		(pad "2" smd roundrect
			(at 0.48 0 90)
			(size 0.59 0.64)
			(layers "B.Cu" "B.Paste" "B.Mask")
			(roundrect_rratio 0.25)
			(net 23 "+3V3")
			(pintype "passive")
		)
	)
	(footprint "antmicro-footprints:R_0402_1005Metric"
		(layer "B.Cu")
		(at 129.794 130.88775 180)
		(descr "Resistor SMD 0402")
		(tags "resistor SMD 0402")
		(property "Reference" "R26"
			(at -3.336 -0.42225 0)
			(layer "B.SilkS")
			(effects
				(font
					(size 0.7 0.7)
					(thickness 0.15)
				)
				(justify left bottom mirror)
			)
		)
		(property "Value" "R_1k_0402"
			(at -1.011843 -1.772047 0)
			(layer "B.Fab")
			(effects
				(font
					(size 0.7 0.7)
					(thickness 0.15)
				)
				(justify left bottom mirror)
			)
		)
		(property "Footprint" "antmicro-footprints:R_0402_1005Metric"
			(at 0 0 0)
			(layer "B.Fab")
			(hide yes)
			(effects
				(font
					(size 1.27 1.27)
					(thickness 0.15)
				)
				(justify mirror)
			)
		)
		(property "Datasheet" "https://www.bourns.com/docs/product-datasheets/cr.pdf"
			(at 0 0 0)
			(layer "B.Fab")
			(hide yes)
			(effects
				(font
					(size 1.27 1.27)
					(thickness 0.15)
				)
				(justify mirror)
			)
		)
		(property "Description" "SMD Chip Resistor, 1 kohm, ± 1%, 63 mW, 0402 [1005 Metric], Thick Film, General Purpose"
			(at 0 0 0)
			(layer "B.Fab")
			(hide yes)
			(effects
				(font
					(size 1.27 1.27)
					(thickness 0.15)
				)
				(justify mirror)
			)
		)
		(property "MPN" "CR0402-FX-1001GLF"
			(at 0 0 0)
			(unlocked yes)
			(layer "B.Fab")
			(hide yes)
			(effects
				(font
					(size 1 1)
					(thickness 0.15)
				)
				(justify mirror)
			)
		)
		(property "Manufacturer" "Bourns"
			(at 0 0 0)
			(unlocked yes)
			(layer "B.Fab")
			(hide yes)
			(effects
				(font
					(size 1 1)
					(thickness 0.15)
				)
				(justify mirror)
			)
		)
		(property "License" "Apache-2.0"
			(at 0 0 0)
			(unlocked yes)
			(layer "B.Fab")
			(hide yes)
			(effects
				(font
					(size 1 1)
					(thickness 0.15)
				)
				(justify mirror)
			)
		)
		(property "Author" "Antmicro"
			(at 0 0 0)
			(unlocked yes)
			(layer "B.Fab")
			(hide yes)
			(effects
				(font
					(size 1 1)
					(thickness 0.15)
				)
				(justify mirror)
			)
		)
		(property "Val" "1k"
			(at 0 0 0)
			(unlocked yes)
			(layer "B.Fab")
			(hide yes)
			(effects
				(font
					(size 1 1)
					(thickness 0.15)
				)
				(justify mirror)
			)
		)
		(property "Tolerance" "1%"
			(at 0 0 0)
			(unlocked yes)
			(layer "B.Fab")
			(hide yes)
			(effects
				(font
					(size 1 1)
					(thickness 0.15)
				)
				(justify mirror)
			)
		)
		(property "Public" "False"
			(at 0 0 0)
			(unlocked yes)
			(layer "B.Fab")
			(hide yes)
			(effects
				(font
					(size 1 1)
					(thickness 0.15)
				)
				(justify mirror)
			)
		)
		(sheetname "Root")
		(sheetfile "jetson-orin-baseboard-oculink-expansion.kicad_sch")
		(attr smd)
		(fp_rect
			(start -0.925 0.47)
			(end 0.925 -0.47)
			(stroke
				(width 0.05)
				(type default)
			)
			(fill none)
			(layer "B.CrtYd")
		)
		(fp_rect
			(start -0.5 0.25)
			(end 0.5 -0.25)
			(stroke
				(width 0.15)
				(type solid)
			)
			(fill none)
			(layer "B.Fab")
		)
		(fp_text user "License: Apache-2.0"
			(at -0.95 -5.169 0)
			(layer "B.Fab")
			(hide yes)
			(effects
				(font
					(size 0.7 0.7)
					(thickness 0.15)
				)
				(justify left bottom mirror)
			)
		)
		(fp_text user "Author: Antmicro"
			(at -0.95 -4.169 0)
			(layer "B.Fab")
			(hide yes)
			(effects
				(font
					(size 0.7 0.7)
					(thickness 0.15)
				)
				(justify left bottom mirror)
			)
		)
		(fp_text user "${REFERENCE}"
			(at -0.95 -3.168 0)
			(layer "B.Fab")
			(hide yes)
			(effects
				(font
					(size 0.7 0.7)
					(thickness 0.15)
				)
				(justify left bottom mirror)
			)
		)
		(pad "1" smd roundrect
			(at -0.48 0 180)
			(size 0.59 0.64)
			(layers "B.Cu" "B.Paste" "B.Mask")
			(roundrect_rratio 0.25)
			(net 51 "GND")
			(pintype "passive")
		)
		(pad "2" smd roundrect
			(at 0.48 0 180)
			(size 0.59 0.64)
			(layers "B.Cu" "B.Paste" "B.Mask")
			(roundrect_rratio 0.25)
			(net 100 "/TX_FG0")
			(pintype "passive")
		)
	)
	(footprint "antmicro-footprints:C_0402_1005Metric"
		(layer "B.Cu")
		(at 124.275 127.914 -90)
		(descr "Capacitor SMD 0402")
		(tags "capacitor SMD 0402")
		(property "Reference" "C17"
			(at 1.626 -0.435 90)
			(layer "B.SilkS")
			(effects
				(font
					(size 0.7 0.7)
					(thickness 0.15)
				)
				(justify left bottom mirror)
			)
		)
		(property "Value" "C_100n_0402"
			(at -1.022927 -2.155213 90)
			(layer "B.Fab")
			(effects
				(font
					(size 0.7 0.7)
					(thickness 0.15)
				)
				(justify left bottom mirror)
			)
		)
		(property "Footprint" "antmicro-footprints:C_0402_1005Metric"
			(at 0 0 90)
			(layer "B.Fab")
			(hide yes)
			(effects
				(font
					(size 1.27 1.27)
					(thickness 0.15)
				)
				(justify mirror)
			)
		)
		(property "Datasheet" "https://www.murata.com/products/productdetail?partno=GRM155R61H104KE14%23"
			(at 0 0 90)
			(layer "B.Fab")
			(hide yes)
			(effects
				(font
					(size 1.27 1.27)
					(thickness 0.15)
				)
				(justify mirror)
			)
		)
		(property "Description" "SMD Multilayer Ceramic Capacitor, 0.1 µF, 50 V, 0402 [1005 Metric], ± 10%, X5R, GRM Series"
			(at 0 0 90)
			(layer "B.Fab")
			(hide yes)
			(effects
				(font
					(size 1.27 1.27)
					(thickness 0.15)
				)
				(justify mirror)
			)
		)
		(property "MPN" "GRM155R61H104KE14D"
			(at 0 0 90)
			(unlocked yes)
			(layer "B.Fab")
			(hide yes)
			(effects
				(font
					(size 1 1)
					(thickness 0.15)
				)
				(justify mirror)
			)
		)
		(property "Manufacturer" "Murata"
			(at 0 0 90)
			(unlocked yes)
			(layer "B.Fab")
			(hide yes)
			(effects
				(font
					(size 1 1)
					(thickness 0.15)
				)
				(justify mirror)
			)
		)
		(property "License" "Apache-2.0"
			(at 0 0 90)
			(unlocked yes)
			(layer "B.Fab")
			(hide yes)
			(effects
				(font
					(size 1 1)
					(thickness 0.15)
				)
				(justify mirror)
			)
		)
		(property "Author" "Antmicro"
			(at 0 0 90)
			(unlocked yes)
			(layer "B.Fab")
			(hide yes)
			(effects
				(font
					(size 1 1)
					(thickness 0.15)
				)
				(justify mirror)
			)
		)
		(property "Val" "100n"
			(at 0 0 90)
			(unlocked yes)
			(layer "B.Fab")
			(hide yes)
			(effects
				(font
					(size 1 1)
					(thickness 0.15)
				)
				(justify mirror)
			)
		)
		(property "Voltage" "50V"
			(at 0 0 90)
			(unlocked yes)
			(layer "B.Fab")
			(hide yes)
			(effects
				(font
					(size 1 1)
					(thickness 0.15)
				)
				(justify mirror)
			)
		)
		(property "Dielectric" "X5R"
			(at 0 0 90)
			(unlocked yes)
			(layer "B.Fab")
			(hide yes)
			(effects
				(font
					(size 1 1)
					(thickness 0.15)
				)
				(justify mirror)
			)
		)
		(property "Public" "False"
			(at 0 0 90)
			(unlocked yes)
			(layer "B.Fab")
			(hide yes)
			(effects
				(font
					(size 1 1)
					(thickness 0.15)
				)
				(justify mirror)
			)
		)
		(sheetname "Root")
		(sheetfile "jetson-orin-baseboard-oculink-expansion.kicad_sch")
		(attr smd)
		(fp_rect
			(start -0.925 0.47)
			(end 0.925 -0.47)
			(stroke
				(width 0.05)
				(type default)
			)
			(fill none)
			(layer "B.CrtYd")
		)
		(fp_line
			(start -0.494 0.25)
			(end -0.494 -0.248)
			(stroke
				(width 0.15)
				(type solid)
			)
			(layer "B.Fab")
		)
		(fp_line
			(start 0.504 0.25)
			(end -0.494 0.25)
			(stroke
				(width 0.15)
				(type solid)
			)
			(layer "B.Fab")
		)
		(fp_line
			(start -0.494 -0.248)
			(end 0.504 -0.248)
			(stroke
				(width 0.15)
				(type solid)
			)
			(layer "B.Fab")
		)
		(fp_line
			(start 0.504 -0.248)
			(end 0.504 0.25)
			(stroke
				(width 0.15)
				(type solid)
			)
			(layer "B.Fab")
		)
		(fp_text user "${REFERENCE}"
			(at -0.939 -4.599 90)
			(layer "B.Fab")
			(hide yes)
			(effects
				(font
					(size 0.7 0.7)
					(thickness 0.15)
				)
				(justify left bottom mirror)
			)
		)
		(fp_text user "License: Apache-2.0"
			(at -0.939 -5.799 90)
			(layer "B.Fab")
			(hide yes)
			(effects
				(font
					(size 0.7 0.7)
					(thickness 0.15)
				)
				(justify left bottom mirror)
			)
		)
		(fp_text user "Author: Antmicro"
			(at -0.939 -3.399 90)
			(layer "B.Fab")
			(hide yes)
			(effects
				(font
					(size 0.7 0.7)
					(thickness 0.15)
				)
				(justify left bottom mirror)
			)
		)
		(pad "1" smd roundrect
			(at -0.48 0 270)
			(size 0.59 0.64)
			(layers "B.Cu" "B.Paste" "B.Mask")
			(roundrect_rratio 0.25)
			(net 51 "GND")
			(pintype "passive")
		)
		(pad "2" smd roundrect
			(at 0.48 0 270)
			(size 0.59 0.64)
			(layers "B.Cu" "B.Paste" "B.Mask")
			(roundrect_rratio 0.25)
			(net 23 "+3V3")
			(pintype "passive")
		)
	)
	(footprint "antmicro-footprints:R_0402_1005Metric"
		(layer "B.Cu")
		(at 127.945 129.54775)
		(descr "Resistor SMD 0402")
		(tags "resistor SMD 0402")
		(property "Reference" "R27"
			(at -3.275 -0.37775 0)
			(layer "B.SilkS")
			(effects
				(font
					(size 0.7 0.7)
					(thickness 0.15)
				)
				(justify right top mirror)
			)
		)
		(property "Value" "R_1k_0402"
			(at -1.011843 -1.772047 0)
			(layer "B.Fab")
			(effects
				(font
					(size 0.7 0.7)
					(thickness 0.15)
				)
				(justify right top mirror)
			)
		)
		(property "Footprint" "antmicro-footprints:R_0402_1005Metric"
			(at 0 0 0)
			(layer "B.Fab")
			(hide yes)
			(effects
				(font
					(size 1.27 1.27)
					(thickness 0.15)
				)
				(justify mirror)
			)
		)
		(property "Datasheet" "https://www.bourns.com/docs/product-datasheets/cr.pdf"
			(at 0 0 0)
			(layer "B.Fab")
			(hide yes)
			(effects
				(font
					(size 1.27 1.27)
					(thickness 0.15)
				)
				(justify mirror)
			)
		)
		(property "Description" "SMD Chip Resistor, 1 kohm, ± 1%, 63 mW, 0402 [1005 Metric], Thick Film, General Purpose"
			(at 0 0 0)
			(layer "B.Fab")
			(hide yes)
			(effects
				(font
					(size 1.27 1.27)
					(thickness 0.15)
				)
				(justify mirror)
			)
		)
		(property "MPN" "CR0402-FX-1001GLF"
			(at 0 0 180)
			(unlocked yes)
			(layer "B.Fab")
			(hide yes)
			(effects
				(font
					(size 1 1)
					(thickness 0.15)
				)
				(justify mirror)
			)
		)
		(property "Manufacturer" "Bourns"
			(at 0 0 180)
			(unlocked yes)
			(layer "B.Fab")
			(hide yes)
			(effects
				(font
					(size 1 1)
					(thickness 0.15)
				)
				(justify mirror)
			)
		)
		(property "License" "Apache-2.0"
			(at 0 0 180)
			(unlocked yes)
			(layer "B.Fab")
			(hide yes)
			(effects
				(font
					(size 1 1)
					(thickness 0.15)
				)
				(justify mirror)
			)
		)
		(property "Author" "Antmicro"
			(at 0 0 180)
			(unlocked yes)
			(layer "B.Fab")
			(hide yes)
			(effects
				(font
					(size 1 1)
					(thickness 0.15)
				)
				(justify mirror)
			)
		)
		(property "Val" "1k"
			(at 0 0 180)
			(unlocked yes)
			(layer "B.Fab")
			(hide yes)
			(effects
				(font
					(size 1 1)
					(thickness 0.15)
				)
				(justify mirror)
			)
		)
		(property "Tolerance" "1%"
			(at 0 0 180)
			(unlocked yes)
			(layer "B.Fab")
			(hide yes)
			(effects
				(font
					(size 1 1)
					(thickness 0.15)
				)
				(justify mirror)
			)
		)
		(property "Public" "False"
			(at 0 0 180)
			(unlocked yes)
			(layer "B.Fab")
			(hide yes)
			(effects
				(font
					(size 1 1)
					(thickness 0.15)
				)
				(justify mirror)
			)
		)
		(sheetname "Root")
		(sheetfile "jetson-orin-baseboard-oculink-expansion.kicad_sch")
		(attr smd)
		(fp_rect
			(start -0.925 0.47)
			(end 0.925 -0.47)
			(stroke
				(width 0.05)
				(type default)
			)
			(fill none)
			(layer "B.CrtYd")
		)
		(fp_rect
			(start -0.5 0.25)
			(end 0.5 -0.25)
			(stroke
				(width 0.15)
				(type solid)
			)
			(fill none)
			(layer "B.Fab")
		)
		(fp_text user "License: Apache-2.0"
			(at -0.95 -5.169 0)
			(layer "B.Fab")
			(hide yes)
			(effects
				(font
					(size 0.7 0.7)
					(thickness 0.15)
				)
				(justify right top mirror)
			)
		)
		(fp_text user "Author: Antmicro"
			(at -0.95 -4.169 0)
			(layer "B.Fab")
			(hide yes)
			(effects
				(font
					(size 0.7 0.7)
					(thickness 0.15)
				)
				(justify right top mirror)
			)
		)
		(fp_text user "${REFERENCE}"
			(at -0.95 -3.168 0)
			(layer "B.Fab")
			(hide yes)
			(effects
				(font
					(size 0.7 0.7)
					(thickness 0.15)
				)
				(justify right top mirror)
			)
		)
		(pad "1" smd roundrect
			(at -0.48 0)
			(size 0.59 0.64)
			(layers "B.Cu" "B.Paste" "B.Mask")
			(roundrect_rratio 0.25)
			(net 23 "+3V3")
			(pintype "passive")
		)
		(pad "2" smd roundrect
			(at 0.48 0)
			(size 0.59 0.64)
			(layers "B.Cu" "B.Paste" "B.Mask")
			(roundrect_rratio 0.25)
			(net 101 "/TX_FG1")
			(pintype "passive")
		)
	)
)
